(kicad_pcb
	(version 20260206)
	(generator "pcbnew")
	(generator_version "10.0")
	(general
		(thickness 1.6)
		(legacy_teardrops no)
	)
	(paper "A4")
	(title_block
		(title "peb — Lightning_PEB_BRD.brd")
		(comment 1 "Lightning (Wiwynn / Facebook NVMe JBOF) / footprints 549-553 of 2563")
	)
	(layers
		(0 "F.Cu" signal "TOP")
		(4 "In1.Cu" signal "L2GND")
		(6 "In2.Cu" signal "L3")
		(8 "In3.Cu" signal "L4VCC")
		(10 "In4.Cu" signal "L5VCC")
		(12 "In5.Cu" signal "L6")
		(14 "In6.Cu" signal "L7GND")
		(2 "B.Cu" signal "BOTTOM")
		(9 "F.Adhes" user "F.Adhesive")
		(11 "B.Adhes" user "B.Adhesive")
		(13 "F.Paste" user "Package Geometry/Pastemask Top")
		(15 "B.Paste" user "Package Geometry/Pastemask Bottom")
		(5 "F.SilkS" user "Ref Des/Silkscreen Top")
		(7 "B.SilkS" user "Ref Des/Silkscreen Bottom")
		(1 "F.Mask" user "Board Geometry/Soldermask Top")
		(3 "B.Mask" user "Board Geometry/Soldermask Bottom")
		(17 "Dwgs.User" user "User.Drawings")
		(19 "Cmts.User" user "User.Comments")
		(21 "Eco1.User" user "User.Eco1")
		(23 "Eco2.User" user "User.Eco2")
		(25 "Edge.Cuts" user "Board Geometry/Outline")
		(27 "Margin" user)
		(31 "F.CrtYd" user "Package Geometry/Place Bound Top")
		(29 "B.CrtYd" user "Package Geometry/Place Bound Bottom")
		(35 "F.Fab" user "Ref Des/Assembly Top")
		(33 "B.Fab" user "Ref Des/Assembly Bottom")
	)
	(footprint ""
		(layer "F.Cu")
		(at 61.708538 -23.136606 90)
		(property "Reference" "CN2"
			(at 0 0 90)
			(layer "F.SilkS")
			(hide yes)
			(effects
				(font
					(size 1.27 1.27)
				)
			)
		)
		(property "Value" "PIN-CONN24A-4-GP"
			(at -10.5156 -7.239 90)
			(unlocked yes)
			(layer "F.Fab")
			(hide yes)
			(effects
				(font
					(size 1.016 1.016)
					(thickness 0.1524)
				)
			)
		)
		(property "Device Type" "232-97-12GBE8"
			(at -10.5156 -8.763 90)
			(unlocked yes)
			(layer "F.Fab")
			(hide yes)
			(effects
				(font
					(size 1.016 1.016)
					(thickness 0.1524)
				)
			)
		)
		(duplicate_pad_numbers_are_jumpers no)
		(fp_line
			(start 7.7724 -3.5052)
			(end -7.7724 -3.5052)
			(stroke
				(width 0.1524)
				(type default)
			)
			(layer "F.SilkS")
		)
		(fp_line
			(start -7.7724 -3.5052)
			(end -7.7724 3.5052)
			(stroke
				(width 0.1524)
				(type default)
			)
			(layer "F.SilkS")
		)
		(fp_line
			(start 7.7724 3.5052)
			(end 7.7724 -3.5052)
			(stroke
				(width 0.1524)
				(type default)
			)
			(layer "F.SilkS")
		)
		(fp_line
			(start -7.7724 3.5052)
			(end 7.7724 3.5052)
			(stroke
				(width 0.1524)
				(type default)
			)
			(layer "F.SilkS")
		)
		(fp_line
			(start -7.4041 3.5941)
			(end -6.5405 3.5941)
			(stroke
				(width 0.3302)
				(type default)
			)
			(layer "F.SilkS")
		)
		(fp_poly
			(pts
				(xy -6.985 3.5814) (xy -7.62 4.2164) (xy -6.35 4.2164)
			)
			(stroke
				(width 0)
				(type default)
			)
			(fill yes)
			(layer "F.SilkS")
		)
		(fp_poly
			(pts
				(xy -7.3406 0.224536) (xy 7.3406 0.224536) (xy 7.3406 -0.224536) (xy -7.3406 -0.224536)
			)
			(stroke
				(width 0)
				(type default)
			)
			(fill yes)
			(layer "F.SilkS")
		)
		(fp_rect
			(start -7.5184 2.7432)
			(end 7.5184 -2.7432)
			(stroke
				(width 0)
				(type default)
			)
			(fill no)
			(layer "F.CrtYd")
		)
		(fp_poly
			(pts
				(xy 8.0264 -2.7432) (xy -7.5184 -2.7432) (xy -7.5184 2.7432) (xy 7.5184 2.7432) (xy 7.5184 -2.7305)
				(xy 8.0264 -2.7305) (xy 8.0264 3.7592) (xy -8.0264 3.7592) (xy -8.0264 -3.7592) (xy 8.0264 -3.7592)
			)
			(stroke
				(width 0)
				(type default)
			)
			(fill no)
			(layer "F.CrtYd")
		)
		(fp_rect
			(start -8.0264 3.7592)
			(end 8.0264 -3.7592)
			(stroke
				(width 0)
				(type default)
			)
			(fill no)
			(layer "F.Fab")
		)
		(pad "1" smd rect
			(at -6.985 1.837436 90)
			(size 0.7112 2.8194)
			(layers "F.Cu" "F.Mask" "F.Paste")
			(net "GND")
		)
		(pad "2" smd rect
			(at -6.985 -1.837436 90)
			(size 0.7112 2.8194)
			(layers "F.Cu" "F.Mask" "F.Paste")
			(net "GND")
		)
		(pad "3" smd rect
			(at -5.715 1.837436 90)
			(size 0.7112 2.8194)
			(layers "F.Cu" "F.Mask" "F.Paste")
			(net "MNG_TX_DN")
		)
		(pad "4" smd rect
			(at -5.715 -1.837436 90)
			(size 0.7112 2.8194)
			(layers "F.Cu" "F.Mask" "F.Paste")
			(net "MNG_TX_DP")
		)
		(pad "5" smd rect
			(at -4.445 1.837436 90)
			(size 0.7112 2.8194)
			(layers "F.Cu" "F.Mask" "F.Paste")
			(net "GND")
		)
		(pad "6" smd rect
			(at -4.445 -1.837436 90)
			(size 0.7112 2.8194)
			(layers "F.Cu" "F.Mask" "F.Paste")
			(net "GND")
		)
		(pad "7" smd rect
			(at -3.175 1.837436 90)
			(size 0.7112 2.8194)
			(layers "F.Cu" "F.Mask" "F.Paste")
			(net "MNG_RX_DN")
		)
		(pad "8" smd rect
			(at -3.175 -1.837436 90)
			(size 0.7112 2.8194)
			(layers "F.Cu" "F.Mask" "F.Paste")
			(net "MNG_RX_DP")
		)
		(pad "9" smd rect
			(at -1.905 1.837436 90)
			(size 0.7112 2.8194)
			(layers "F.Cu" "F.Mask" "F.Paste")
			(net "GND")
		)
		(pad "10" smd rect
			(at -1.905 -1.837436 90)
			(size 0.7112 2.8194)
			(layers "F.Cu" "F.Mask" "F.Paste")
			(net "GND")
		)
		(pad "11" smd rect
			(at -0.635 1.837436 90)
			(size 0.7112 2.8194)
			(layers "F.Cu" "F.Mask" "F.Paste")
			(net "TRAY_ID1")
		)
		(pad "12" smd rect
			(at -0.635 -1.837436 90)
			(size 0.7112 2.8194)
			(layers "F.Cu" "F.Mask" "F.Paste")
			(net "TRAY_ID2")
		)
		(pad "13" smd rect
			(at 0.635 1.837436 90)
			(size 0.7112 2.8194)
			(layers "F.Cu" "F.Mask" "F.Paste")
			(net "BMC_INT_N")
		)
		(pad "14" smd rect
			(at 0.635 -1.837436 90)
			(size 0.7112 2.8194)
			(layers "F.Cu" "F.Mask" "F.Paste")
			(net "TRAY_ID0")
		)
		(pad "15" smd rect
			(at 1.905 1.837436 90)
			(size 0.7112 2.8194)
			(layers "F.Cu" "F.Mask" "F.Paste")
			(net "IPMB_DAT")
		)
		(pad "16" smd rect
			(at 1.905 -1.837436 90)
			(size 0.7112 2.8194)
			(layers "F.Cu" "F.Mask" "F.Paste")
			(net "IPMB_CLK")
		)
		(pad "17" smd rect
			(at 3.175 1.837436 90)
			(size 0.7112 2.8194)
			(layers "F.Cu" "F.Mask" "F.Paste")
			(net "TRAY_RESET_N")
		)
		(pad "18" smd rect
			(at 3.175 -1.837436 90)
			(size 0.7112 2.8194)
			(layers "F.Cu" "F.Mask" "F.Paste")
			(net "BP_PRSNT_N")
		)
		(pad "19" smd rect
			(at 4.445 1.837436 90)
			(size 0.7112 2.8194)
			(layers "F.Cu" "F.Mask" "F.Paste")
			(net "MBP_UART_TX")
		)
		(pad "20" smd rect
			(at 4.445 -1.837436 90)
			(size 0.7112 2.8194)
			(layers "F.Cu" "F.Mask" "F.Paste")
			(net "MBP_UART_RX")
		)
		(pad "21" smd rect
			(at 5.715 1.837436 90)
			(size 0.7112 2.8194)
			(layers "F.Cu" "F.Mask" "F.Paste")
			(net "Net_85")
		)
		(pad "22" smd rect
			(at 5.715 -1.837436 90)
			(size 0.7112 2.8194)
			(layers "F.Cu" "F.Mask" "F.Paste")
			(net "Net_84")
		)
		(pad "23" smd rect
			(at 6.985 1.837436 90)
			(size 0.7112 2.8194)
			(layers "F.Cu" "F.Mask" "F.Paste")
			(net "TRAY_POWER_CRIT_N")
		)
		(pad "24" smd rect
			(at 6.985 -1.837436 90)
			(size 0.7112 2.8194)
			(layers "F.Cu" "F.Mask" "F.Paste")
			(net "CN2_P23")
		)
		(zone
			(layer "F.Cu")
			(hatch none 0.5)
			(connect_pads
				(clearance 0)
			)
			(min_thickness 0.25)
			(keepout
				(tracks not_allowed)
				(vias allowed)
				(pads allowed)
				(copperpour not_allowed)
				(footprints allowed)
			)
			(placement
				(enabled no)
				(sheetname "")
			)
			(fill
				(thermal_gap 0.5)
				(thermal_bridge_width 0.5)
				(island_removal_mode 0)
			)
			(polygon
				(pts
					(xy 62.136274 -15.796006) (xy 62.136274 -30.477206) (xy 61.280802 -30.477206) (xy 61.280802 -15.796006)
				)
			)
		)
		(zone
			(layer "F.Cu")
			(hatch none 0.5)
			(connect_pads
				(clearance 0)
			)
			(min_thickness 0.25)
			(keepout
				(tracks allowed)
				(vias not_allowed)
				(pads allowed)
				(copperpour not_allowed)
				(footprints allowed)
			)
			(placement
				(enabled no)
				(sheetname "")
			)
			(fill
				(thermal_gap 0.5)
				(thermal_bridge_width 0.5)
				(island_removal_mode 0)
			)
			(polygon
				(pts
					(xy 62.136274 -15.796006) (xy 62.136274 -30.477206) (xy 61.280802 -30.477206) (xy 61.280802 -15.796006)
				)
			)
		)
	)
	(footprint ""
		(layer "F.Cu")
		(at 161.80816 -212.420454 180)
		(property "Reference" "C165"
			(at 0 0 180)
			(layer "F.SilkS")
			(hide yes)
			(effects
				(font
					(size 1.27 1.27)
				)
			)
		)
		(property "Value" "SCD22U10V2KX-1GP"
			(at 1.1811 -2.7051 180)
			(unlocked yes)
			(layer "F.Fab")
			(hide yes)
			(effects
				(font
					(size 1.016 1.016)
					(thickness 0.1524)
				)
			)
		)
		(property "Device Type" "C402H22"
			(at 1.1811 -4.2291 180)
			(unlocked yes)
			(layer "F.Fab")
			(hide yes)
			(effects
				(font
					(size 1.016 1.016)
					(thickness 0.1524)
				)
			)
		)
		(duplicate_pad_numbers_are_jumpers no)
		(fp_rect
			(start -0.4318 0.9525)
			(end 0.4318 -0.9525)
			(stroke
				(width 0)
				(type default)
			)
			(fill no)
			(layer "F.CrtYd")
		)
		(fp_rect
			(start -0.4318 0.9525)
			(end 0.4318 -0.9525)
			(stroke
				(width 0)
				(type default)
			)
			(fill no)
			(layer "F.Fab")
		)
		(pad "1" smd custom
			(at 0 -0.4445 180)
			(size 0.1524 0.1524)
			(layers "F.Cu" "F.Mask" "F.Paste")
			(net "PCIE_TX_CAP_N52")
			(options
				(clearance outline)
				(anchor circle)
			)
			(primitives
				(gr_poly
					(pts
						(arc
							(start 0.3048 -0.2032)
							(mid 0.275042 -0.275042)
							(end 0.2032 -0.3048)
						)
						(arc
							(start -0.2032 -0.3048)
							(mid -0.275042 -0.275042)
							(end -0.3048 -0.2032)
						)
						(arc
							(start -0.3048 0.2032)
							(mid -0.275042 0.275042)
							(end -0.2032 0.3048)
						)
						(arc
							(start 0.2032 0.3048)
							(mid 0.275042 0.275042)
							(end 0.3048 0.2032)
						)
					)
					(width 0)
					(fill yes)
				)
			)
		)
		(pad "2" smd custom
			(at 0 0.4445 180)
			(size 0.1524 0.1524)
			(layers "F.Cu" "F.Mask" "F.Paste")
			(net "PCIE_TX_N52")
			(options
				(clearance outline)
				(anchor circle)
			)
			(primitives
				(gr_poly
					(pts
						(arc
							(start 0.3048 -0.2032)
							(mid 0.275042 -0.275042)
							(end 0.2032 -0.3048)
						)
						(arc
							(start -0.2032 -0.3048)
							(mid -0.275042 -0.275042)
							(end -0.3048 -0.2032)
						)
						(arc
							(start -0.3048 0.2032)
							(mid -0.275042 0.275042)
							(end -0.2032 0.3048)
						)
						(arc
							(start 0.2032 0.3048)
							(mid 0.275042 0.275042)
							(end 0.3048 0.2032)
						)
					)
					(width 0)
					(fill yes)
				)
			)
		)
	)
	(footprint ""
		(layer "F.Cu")
		(at 186.6392 -3.556 90)
		(property "Reference" "R496"
			(at 0 0 90)
			(layer "F.SilkS")
			(hide yes)
			(effects
				(font
					(size 1.27 1.27)
				)
			)
		)
		(property "Value" "0R2J-2-GP"
			(at 0.064008 -3.993896 90)
			(unlocked yes)
			(layer "F.Fab")
			(hide yes)
			(effects
				(font
					(size 1.016 1.016)
					(thickness 0.1524)
				)
			)
		)
		(property "Device Type" "R402H16"
			(at 0.064008 -5.517896 90)
			(unlocked yes)
			(layer "F.Fab")
			(hide yes)
			(effects
				(font
					(size 1.016 1.016)
					(thickness 0.1524)
				)
			)
		)
		(duplicate_pad_numbers_are_jumpers no)
		(fp_line
			(start 0.508 -0.9398)
			(end -0.508 -0.9398)
			(stroke
				(width 0.1524)
				(type default)
			)
			(layer "F.SilkS")
		)
		(fp_line
			(start -0.508 -0.9398)
			(end -0.508 0.9398)
			(stroke
				(width 0.1524)
				(type default)
			)
			(layer "F.SilkS")
		)
		(fp_rect
			(start -0.508 0.9398)
			(end 0.508 -0.9398)
			(stroke
				(width 0)
				(type default)
			)
			(fill no)
			(layer "F.CrtYd")
		)
		(fp_rect
			(start -0.508 0.9398)
			(end 0.508 -0.9398)
			(stroke
				(width 0)
				(type default)
			)
			(fill no)
			(layer "F.Fab")
		)
		(pad "1" smd custom
			(at 0 -0.4445 90)
			(size 0.1397 0.1397)
			(layers "F.Cu" "F.Mask" "F.Paste")
			(net "HB_OUT_BMC")
			(options
				(clearance outline)
				(anchor circle)
			)
			(primitives
				(gr_poly
					(pts
						(arc
							(start -0.1778 -0.2794)
							(mid -0.249642 -0.249642)
							(end -0.2794 -0.1778)
						)
						(arc
							(start -0.2794 0.1778)
							(mid -0.249642 0.249642)
							(end -0.1778 0.2794)
						)
						(arc
							(start 0.1778 0.2794)
							(mid 0.249642 0.249642)
							(end 0.2794 0.1778)
						)
						(arc
							(start 0.2794 -0.1778)
							(mid 0.249642 -0.249642)
							(end 0.1778 -0.2794)
						)
					)
					(width 0)
					(fill yes)
				)
			)
		)
		(pad "2" smd custom
			(at 0 0.4445 90)
			(size 0.1397 0.1397)
			(layers "F.Cu" "F.Mask" "F.Paste")
			(net "Q21_G")
			(options
				(clearance outline)
				(anchor circle)
			)
			(primitives
				(gr_poly
					(pts
						(arc
							(start -0.1778 -0.2794)
							(mid -0.249642 -0.249642)
							(end -0.2794 -0.1778)
						)
						(arc
							(start -0.2794 0.1778)
							(mid -0.249642 0.249642)
							(end -0.1778 0.2794)
						)
						(arc
							(start 0.1778 0.2794)
							(mid 0.249642 0.249642)
							(end 0.2794 0.1778)
						)
						(arc
							(start 0.2794 -0.1778)
							(mid 0.249642 -0.249642)
							(end 0.1778 -0.2794)
						)
					)
					(width 0)
					(fill yes)
				)
			)
		)
	)
	(footprint ""
		(layer "F.Cu")
		(at 43.228768 -118.307104)
		(property "Reference" "TP218"
			(at 0 0 0)
			(layer "F.SilkS")
			(hide yes)
			(effects
				(font
					(size 1.27 1.27)
				)
			)
		)
		(property "Value" "TPAD28-2-GP"
			(at -0.0127 -1.6637 0)
			(unlocked yes)
			(layer "F.Fab")
			(hide yes)
			(effects
				(font
					(size 1.016 1.016)
					(thickness 0.1524)
				)
			)
		)
		(property "Device Type" "TPAD28"
			(at -0.0127 -3.1877 0)
			(unlocked yes)
			(layer "F.Fab")
			(hide yes)
			(effects
				(font
					(size 1.016 1.016)
					(thickness 0.1524)
				)
			)
		)
		(duplicate_pad_numbers_are_jumpers no)
		(fp_poly
			(pts
				(arc
					(start 0.3556 0)
					(mid -0.3556 0)
					(end 0.3556 0)
				)
			)
			(stroke
				(width 0)
				(type default)
			)
			(fill no)
			(layer "F.CrtYd")
		)
		(fp_poly
			(pts
				(arc
					(start 0.6096 0)
					(mid -0.6096 0)
					(end 0.6096 0)
				)
			)
			(stroke
				(width 0)
				(type default)
			)
			(fill no)
			(layer "F.Fab")
		)
		(pad "1" smd circle
			(at 0 0)
			(size 0.7112 0.7112)
			(layers "F.Cu" "F.Mask" "F.Paste")
			(net "GPIOH0")
		)
	)
	(footprint ""
		(layer "F.Cu")
		(at 128.373124 -202.793092)
		(property "Reference" "U199"
			(at 0 0 0)
			(layer "F.SilkS")
			(hide yes)
			(effects
				(font
					(size 1.27 1.27)
				)
			)
		)
		(property "Value" "MAX7311AUG-GP"
			(at 0 -12.1412 0)
			(unlocked yes)
			(layer "F.Fab")
			(hide yes)
			(effects
				(font
					(size 1.016 1.016)
					(thickness 0.1524)
				)
			)
		)
		(property "Device Type" "TSOIC24H44"
			(at 0 -13.6652 0)
			(unlocked yes)
			(layer "F.Fab")
			(hide yes)
			(effects
				(font
					(size 1.016 1.016)
					(thickness 0.1524)
				)
			)
		)
		(duplicate_pad_numbers_are_jumpers no)
		(fp_line
			(start -4.1148 -1.778)
			(end -4.1148 1.778)
			(stroke
				(width 0.1524)
				(type default)
			)
			(layer "F.SilkS")
		)
		(fp_line
			(start -4.1148 -1.778)
			(end 3.683 -1.778)
			(stroke
				(width 0.1524)
				(type default)
			)
			(layer "F.SilkS")
		)
		(fp_line
			(start -4.0386 1.778)
			(end -4.0386 3.556)
			(stroke
				(width 0.3556)
				(type default)
			)
			(layer "F.SilkS")
		)
		(fp_line
			(start -3.8354 0)
			(end -4.1148 -0.2794)
			(stroke
				(width 0.1524)
				(type default)
			)
			(layer "F.SilkS")
		)
		(fp_line
			(start -3.8354 0)
			(end -4.1148 0.2794)
			(stroke
				(width 0.1524)
				(type default)
			)
			(layer "F.SilkS")
		)
		(fp_line
			(start 3.683 -1.778)
			(end 3.683 1.778)
			(stroke
				(width 0.1524)
				(type default)
			)
			(layer "F.SilkS")
		)
		(fp_line
			(start 3.683 1.778)
			(end -4.1148 1.778)
			(stroke
				(width 0.1524)
				(type default)
			)
			(layer "F.SilkS")
		)
		(fp_poly
			(pts
				(xy -3.7592 -1.778) (xy 3.683 -1.778) (xy 3.683 1.778) (xy -3.7592 1.778)
			)
			(stroke
				(width 0)
				(type default)
			)
			(fill yes)
			(layer "F.SilkS")
		)
		(fp_poly
			(pts
				(xy -4.22656 3.81) (xy 4.22656 3.81) (xy 4.22656 -3.81) (xy -4.22656 -3.81)
			)
			(stroke
				(width 0)
				(type default)
			)
			(fill no)
			(layer "F.CrtYd")
		)
		(fp_poly
			(pts
				(xy -4.22656 -3.81) (xy 4.22656 -3.81) (xy 4.22656 3.81) (xy -4.22656 3.81)
			)
			(stroke
				(width 0)
				(type default)
			)
			(fill no)
			(layer "F.Fab")
		)
		(pad "1" smd rect
			(at -3.57632 2.8194)
			(size 0.3556 1.524)
			(layers "F.Cu" "F.Mask" "F.Paste")
			(net "IOEXP_INT#_2")
		)
		(pad "2" smd rect
			(at -2.92608 2.8194)
			(size 0.3556 1.524)
			(layers "F.Cu" "F.Mask" "F.Paste")
			(net "IOEXP2_AD1")
		)
		(pad "3" smd rect
			(at -2.27584 2.8194)
			(size 0.3556 1.524)
			(layers "F.Cu" "F.Mask" "F.Paste")
			(net "IOEXP2_AD2")
		)
		(pad "4" smd rect
			(at -1.6256 2.8194)
			(size 0.3556 1.524)
			(layers "F.Cu" "F.Mask" "F.Paste")
			(net "SSD_PRSNT#1")
		)
		(pad "5" smd rect
			(at -0.97536 2.8194)
			(size 0.3556 1.524)
			(layers "F.Cu" "F.Mask" "F.Paste")
			(net "SSD_ATNLED#1")
		)
		(pad "6" smd rect
			(at -0.32512 2.8194)
			(size 0.3556 1.524)
			(layers "F.Cu" "F.Mask" "F.Paste")
			(net "SSD_PWREN1")
		)
		(pad "7" smd rect
			(at 0.32512 2.8194)
			(size 0.3556 1.524)
			(layers "F.Cu" "F.Mask" "F.Paste")
			(net "SSD_PERST#1")
		)
		(pad "8" smd rect
			(at 0.97536 2.8194)
			(size 0.3556 1.524)
			(layers "F.Cu" "F.Mask" "F.Paste")
			(net "SSD_PRSNT#2")
		)
		(pad "9" smd rect
			(at 1.6256 2.8194)
			(size 0.3556 1.524)
			(layers "F.Cu" "F.Mask" "F.Paste")
			(net "SSD_ATNLED#2")
		)
		(pad "10" smd rect
			(at 2.27584 2.8194)
			(size 0.3556 1.524)
			(layers "F.Cu" "F.Mask" "F.Paste")
			(net "SSD_PWREN2")
		)
		(pad "11" smd rect
			(at 2.92608 2.8194)
			(size 0.3556 1.524)
			(layers "F.Cu" "F.Mask" "F.Paste")
			(net "SSD_PERST#2")
		)
		(pad "12" smd rect
			(at 3.57632 2.8194)
			(size 0.3556 1.524)
			(layers "F.Cu" "F.Mask" "F.Paste")
			(net "GND")
		)
		(pad "13" smd rect
			(at 3.57632 -2.8194)
			(size 0.3556 1.524)
			(layers "F.Cu" "F.Mask" "F.Paste")
			(net "SSD_PRSNT#6")
		)
		(pad "14" smd rect
			(at 2.92608 -2.8194)
			(size 0.3556 1.524)
			(layers "F.Cu" "F.Mask" "F.Paste")
			(net "SSD_ATNLED#6")
		)
		(pad "15" smd rect
			(at 2.27584 -2.8194)
			(size 0.3556 1.524)
			(layers "F.Cu" "F.Mask" "F.Paste")
			(net "SSD_PWREN6")
		)
		(pad "16" smd rect
			(at 1.6256 -2.8194)
			(size 0.3556 1.524)
			(layers "F.Cu" "F.Mask" "F.Paste")
			(net "SSD_PERST#6")
		)
		(pad "17" smd rect
			(at 0.97536 -2.8194)
			(size 0.3556 1.524)
			(layers "F.Cu" "F.Mask" "F.Paste")
			(net "SSD_PRSNT#7")
		)
		(pad "18" smd rect
			(at 0.32512 -2.8194)
			(size 0.3556 1.524)
			(layers "F.Cu" "F.Mask" "F.Paste")
			(net "SSD_ATNLED#7")
		)
		(pad "19" smd rect
			(at -0.32512 -2.8194)
			(size 0.3556 1.524)
			(layers "F.Cu" "F.Mask" "F.Paste")
			(net "SSD_PWREN7")
		)
		(pad "20" smd rect
			(at -0.97536 -2.8194)
			(size 0.3556 1.524)
			(layers "F.Cu" "F.Mask" "F.Paste")
			(net "SSD_PERST#7")
		)
		(pad "21" smd rect
			(at -1.6256 -2.8194)
			(size 0.3556 1.524)
			(layers "F.Cu" "F.Mask" "F.Paste")
			(net "IOEXP2_AD0")
		)
		(pad "22" smd rect
			(at -2.27584 -2.8194)
			(size 0.3556 1.524)
			(layers "F.Cu" "F.Mask" "F.Paste")
			(net "I2C_GPIO_SCL_2")
		)
		(pad "23" smd rect
			(at -2.92608 -2.8194)
			(size 0.3556 1.524)
			(layers "F.Cu" "F.Mask" "F.Paste")
			(net "I2C_GPIO_SDA_2")
		)
		(pad "24" smd rect
			(at -3.57632 -2.8194)
			(size 0.3556 1.524)
			(layers "F.Cu" "F.Mask" "F.Paste")
			(net "P3V3_STBY")
		)
	)
)
